# SCM (Grand Teton) — schematic netlist excerpt (pin names and nets, part order shuffled) for the footprints in the layout excerpt that follows; sources: Cadence DE-HDL packaged netlist, KiCad conversion of 12092022_DA0F0TMDCD0_F0T_Management_Board_D_brd_V3_OCP.brd

R570  Q_RES  33.2 1% CHIP  pkg 0402LF  page 12 : A = SMB_BMC_MM7_R_SDA ; B = SMB_BMC_MM7_SDA
R416  Q_RES  4.7K 1% CHIP  pkg 0402LF  page 26 : A = P3V3_AUX ; B = TMC75_A0

(kicad_pcb
	(version 20260206)
	(generator "pcbnew")
	(generator_version "10.0")
	(general
		(thickness 1.6)
		(legacy_teardrops no)
	)
	(paper "A4")
	(title_block
		(title "12092022_DA0F0TMDCD0_F0T_Management_Board_D_brd_V3_OCP.brd")
		(comment 1 "Grand Teton / footprints 857-858 of 1440")
	)
	(layers
		(0 "F.Cu" signal "TOP")
		(4 "In1.Cu" signal "GND")
		(6 "In2.Cu" signal "IN1")
		(8 "In3.Cu" signal "GND1")
		(10 "In4.Cu" signal "IN2")
		(12 "In5.Cu" signal "VCC")
		(14 "In6.Cu" signal "VCC1")
		(16 "In7.Cu" signal "IN3")
		(18 "In8.Cu" signal "GND2")
		(20 "In9.Cu" signal "IN4")
		(22 "In10.Cu" signal "GND3")
		(2 "B.Cu" signal "BOTTOM")
		(9 "F.Adhes" user "F.Adhesive")
		(11 "B.Adhes" user "B.Adhesive")
		(13 "F.Paste" user "Package Geometry/Pastemask Top")
		(15 "B.Paste" user "Package Geometry/Pastemask Bottom")
		(5 "F.SilkS" user "Ref Des/Silkscreen Top")
		(7 "B.SilkS" user "Ref Des/Silkscreen Bottom")
		(1 "F.Mask" user "Board Geometry/Soldermask Top")
		(3 "B.Mask" user "Board Geometry/Soldermask Bottom")
		(17 "Dwgs.User" user "User.Drawings")
		(19 "Cmts.User" user "User.Comments")
		(21 "Eco1.User" user "User.Eco1")
		(23 "Eco2.User" user "User.Eco2")
		(25 "Edge.Cuts" user "Board Geometry/Outline")
		(27 "Margin" user)
		(31 "F.CrtYd" user "Package Geometry/Place Bound Top")
		(29 "B.CrtYd" user "Package Geometry/Place Bound Bottom")
		(35 "F.Fab" user "Ref Des/Assembly Top")
		(33 "B.Fab" user "Ref Des/Assembly Bottom")
	)
	(footprint ""
		(layer "B.Cu")
		(at 17.399 -17.907 -90)
		(property "Reference" "R416"
			(at 0 0 90)
			(layer "B.SilkS")
			(hide yes)
			(effects
				(font
					(size 1.27 1.27)
				)
				(justify mirror)
			)
		)
		(property "Value" ""
			(at 0 0 90)
			(layer "B.Fab")
			(effects
				(font
					(size 1.27 1.27)
				)
				(justify mirror)
			)
		)
		(duplicate_pad_numbers_are_jumpers no)
		(fp_line
			(start -0.7874 0.4064)
			(end 0.7874 0.4064)
			(stroke
				(width 0.1524)
				(type default)
			)
			(layer "B.SilkS")
		)
		(fp_line
			(start 0.7874 0.4064)
			(end 0.7874 -0.4064)
			(stroke
				(width 0.1524)
				(type default)
			)
			(layer "B.SilkS")
		)
		(fp_line
			(start -0.7874 -0.4064)
			(end -0.7874 0.4064)
			(stroke
				(width 0.1524)
				(type default)
			)
			(layer "B.SilkS")
		)
		(fp_line
			(start 0.7874 -0.4064)
			(end -0.7874 -0.4064)
			(stroke
				(width 0.1524)
				(type default)
			)
			(layer "B.SilkS")
		)
		(fp_line
			(start -0.67945 0.3048)
			(end -0.120396 0.3048)
			(stroke
				(width 0.1)
				(type default)
			)
			(layer "B.Fab")
		)
		(fp_line
			(start -0.120396 0.3048)
			(end -0.120396 0.2794)
			(stroke
				(width 0.1)
				(type default)
			)
			(layer "B.Fab")
		)
		(fp_line
			(start 0.12065 0.3048)
			(end 0.67945 0.3048)
			(stroke
				(width 0.1)
				(type default)
			)
			(layer "B.Fab")
		)
		(fp_line
			(start 0.67945 0.3048)
			(end 0.67945 -0.305054)
			(stroke
				(width 0.1)
				(type default)
			)
			(layer "B.Fab")
		)
		(fp_line
			(start -0.120396 0.2794)
			(end 0.12065 0.2794)
			(stroke
				(width 0.1)
				(type default)
			)
			(layer "B.Fab")
		)
		(fp_line
			(start 0.12065 0.2794)
			(end 0.12065 0.3048)
			(stroke
				(width 0.1)
				(type default)
			)
			(layer "B.Fab")
		)
		(fp_line
			(start -0.12065 -0.2794)
			(end -0.12065 -0.3048)
			(stroke
				(width 0.1)
				(type default)
			)
			(layer "B.Fab")
		)
		(fp_line
			(start 0.12065 -0.2794)
			(end -0.12065 -0.2794)
			(stroke
				(width 0.1)
				(type default)
			)
			(layer "B.Fab")
		)
		(fp_line
			(start -0.67945 -0.3048)
			(end -0.67945 0.3048)
			(stroke
				(width 0.1)
				(type default)
			)
			(layer "B.Fab")
		)
		(fp_line
			(start -0.12065 -0.3048)
			(end -0.67945 -0.3048)
			(stroke
				(width 0.1)
				(type default)
			)
			(layer "B.Fab")
		)
		(fp_line
			(start 0.12065 -0.305054)
			(end 0.12065 -0.2794)
			(stroke
				(width 0.1)
				(type default)
			)
			(layer "B.Fab")
		)
		(fp_line
			(start 0.67945 -0.305054)
			(end 0.12065 -0.305054)
			(stroke
				(width 0.1)
				(type default)
			)
			(layer "B.Fab")
		)
		(pad "1" smd circle
			(at 0.40005 0 90)
			(size 0 0)
			(layers "B.Cu" "B.Mask" "B.Paste")
			(net "P3V3_AUX")
		)
		(pad "2" smd circle
			(at -0.40005 0 90)
			(size 0 0)
			(layers "B.Cu" "B.Mask" "B.Paste")
			(net "TMC75_A0")
		)
	)
	(footprint ""
		(layer "B.Cu")
		(at 64.1604 -32.4612 90)
		(property "Reference" "R570"
			(at 0 0 90)
			(layer "B.SilkS")
			(hide yes)
			(effects
				(font
					(size 1.27 1.27)
				)
				(justify mirror)
			)
		)
		(property "Value" ""
			(at 0 0 90)
			(layer "B.Fab")
			(effects
				(font
					(size 1.27 1.27)
				)
				(justify mirror)
			)
		)
		(duplicate_pad_numbers_are_jumpers no)
		(fp_line
			(start 0.7874 -0.4064)
			(end -0.7874 -0.4064)
			(stroke
				(width 0.1524)
				(type default)
			)
			(layer "B.SilkS")
		)
		(fp_line
			(start -0.7874 -0.4064)
			(end -0.7874 0.4064)
			(stroke
				(width 0.1524)
				(type default)
			)
			(layer "B.SilkS")
		)
		(fp_line
			(start 0.7874 0.4064)
			(end 0.7874 -0.4064)
			(stroke
				(width 0.1524)
				(type default)
			)
			(layer "B.SilkS")
		)
		(fp_line
			(start -0.7874 0.4064)
			(end 0.7874 0.4064)
			(stroke
				(width 0.1524)
				(type default)
			)
			(layer "B.SilkS")
		)
		(fp_line
			(start 0.67945 -0.305054)
			(end 0.12065 -0.305054)
			(stroke
				(width 0.1)
				(type default)
			)
			(layer "B.Fab")
		)
		(fp_line
			(start 0.12065 -0.305054)
			(end 0.12065 -0.2794)
			(stroke
				(width 0.1)
				(type default)
			)
			(layer "B.Fab")
		)
		(fp_line
			(start -0.12065 -0.3048)
			(end -0.67945 -0.3048)
			(stroke
				(width 0.1)
				(type default)
			)
			(layer "B.Fab")
		)
		(fp_line
			(start -0.67945 -0.3048)
			(end -0.67945 0.3048)
			(stroke
				(width 0.1)
				(type default)
			)
			(layer "B.Fab")
		)
		(fp_line
			(start 0.12065 -0.2794)
			(end -0.12065 -0.2794)
			(stroke
				(width 0.1)
				(type default)
			)
			(layer "B.Fab")
		)
		(fp_line
			(start -0.12065 -0.2794)
			(end -0.12065 -0.3048)
			(stroke
				(width 0.1)
				(type default)
			)
			(layer "B.Fab")
		)
		(fp_line
			(start 0.12065 0.2794)
			(end 0.12065 0.3048)
			(stroke
				(width 0.1)
				(type default)
			)
			(layer "B.Fab")
		)
		(fp_line
			(start -0.120396 0.2794)
			(end 0.12065 0.2794)
			(stroke
				(width 0.1)
				(type default)
			)
			(layer "B.Fab")
		)
		(fp_line
			(start 0.67945 0.3048)
			(end 0.67945 -0.305054)
			(stroke
				(width 0.1)
				(type default)
			)
			(layer "B.Fab")
		)
		(fp_line
			(start 0.12065 0.3048)
			(end 0.67945 0.3048)
			(stroke
				(width 0.1)
				(type default)
			)
			(layer "B.Fab")
		)
		(fp_line
			(start -0.120396 0.3048)
			(end -0.120396 0.2794)
			(stroke
				(width 0.1)
				(type default)
			)
			(layer "B.Fab")
		)
		(fp_line
			(start -0.67945 0.3048)
			(end -0.120396 0.3048)
			(stroke
				(width 0.1)
				(type default)
			)
			(layer "B.Fab")
		)
		(pad "1" smd circle
			(at 0.40005 0 270)
			(size 0 0)
			(layers "B.Cu" "B.Mask" "B.Paste")
			(net "SMB_BMC_MM7_R_SDA")
		)
		(pad "2" smd circle
			(at -0.40005 0 270)
			(size 0 0)
			(layers "B.Cu" "B.Mask" "B.Paste")
			(net "SMB_BMC_MM7_SDA")
		)
	)
)
